# T6G (Grand Teton) — schematic netlist excerpt (pin names and nets, part order shuffled) for the footprints in the layout excerpt that follows; sources: Cadence DE-HDL packaged netlist, KiCad conversion of 04192023_DAF0TMB3IC0_F0TG_MB_C_brd_V02_OCP.brd

R832  Q_RES  0 5% CHIP  pkg 0201LF  page 185 : A = SMB_RT_CPU0_P2_ROM_MUX_2D_R_SDA ; B = SMB_RT_CPU0_P2_ROM_MUX_2D_SDA
R3776  Q_RES  0 5% CHIP  pkg 0402LF  page 150 : A = FM_UARTSW_MSB_N ; B = FM_UARTSW_MSB_R
C6037  Q_CAP  0.01UF 50V 10% X7R  pkg C0402  page 177 : A = P1V2_CPU0_USB_DVDD12 ; B = GND

(kicad_pcb
	(version 20260206)
	(generator "pcbnew")
	(generator_version "10.0")
	(general
		(thickness 1.6)
		(legacy_teardrops no)
	)
	(paper "A4")
	(title_block
		(title "04192023_DAF0TMB3IC0_F0TG_MB_C_brd_V02_OCP.brd")
		(comment 1 "Grand Teton / footprints 7242-7244 of 8354")
	)
	(layers
		(0 "F.Cu" signal "TOP")
		(4 "In1.Cu" signal "GND")
		(6 "In2.Cu" signal "IN1")
		(8 "In3.Cu" signal "GND1")
		(10 "In4.Cu" signal "IN2")
		(12 "In5.Cu" signal "GND2")
		(14 "In6.Cu" signal "IN3")
		(16 "In7.Cu" signal "GND3")
		(18 "In8.Cu" signal "VCC")
		(20 "In9.Cu" signal "VCC1")
		(22 "In10.Cu" signal "GND4")
		(24 "In11.Cu" signal "IN4")
		(26 "In12.Cu" signal "GND5")
		(28 "In13.Cu" signal "IN5")
		(30 "In14.Cu" signal "GND6")
		(32 "In15.Cu" signal "IN6")
		(34 "In16.Cu" signal "GND7")
		(2 "B.Cu" signal "BOTTOM")
		(9 "F.Adhes" user "F.Adhesive")
		(11 "B.Adhes" user "B.Adhesive")
		(13 "F.Paste" user "Package Geometry/Pastemask Top")
		(15 "B.Paste" user "Package Geometry/Pastemask Bottom")
		(5 "F.SilkS" user "Ref Des/Silkscreen Top")
		(7 "B.SilkS" user "Ref Des/Silkscreen Bottom")
		(1 "F.Mask" user "Board Geometry/Soldermask Top")
		(3 "B.Mask" user "Board Geometry/Soldermask Bottom")
		(17 "Dwgs.User" user "User.Drawings")
		(19 "Cmts.User" user "User.Comments")
		(21 "Eco1.User" user "User.Eco1")
		(23 "Eco2.User" user "User.Eco2")
		(25 "Edge.Cuts" user "Board Geometry/Outline")
		(27 "Margin" user)
		(31 "F.CrtYd" user "Package Geometry/Place Bound Top")
		(29 "B.CrtYd" user "Package Geometry/Place Bound Bottom")
		(35 "F.Fab" user "Ref Des/Assembly Top")
		(33 "B.Fab" user "Ref Des/Assembly Bottom")
	)
	(footprint ""
		(layer "B.Cu")
		(at 140.61948 -9.083548 -90)
		(property "Reference" "R3776"
			(at 0 0 90)
			(layer "B.SilkS")
			(hide yes)
			(effects
				(font
					(size 1.27 1.27)
				)
				(justify mirror)
			)
		)
		(property "Value" ""
			(at 0 0 90)
			(layer "B.Fab")
			(effects
				(font
					(size 1.27 1.27)
				)
				(justify mirror)
			)
		)
		(duplicate_pad_numbers_are_jumpers no)
		(fp_line
			(start -0.7874 0.4064)
			(end 0.7874 0.4064)
			(stroke
				(width 0.1524)
				(type default)
			)
			(layer "B.SilkS")
		)
		(fp_line
			(start 0.7874 0.4064)
			(end 0.7874 -0.4064)
			(stroke
				(width 0.1524)
				(type default)
			)
			(layer "B.SilkS")
		)
		(fp_line
			(start -0.7874 -0.4064)
			(end -0.7874 0.4064)
			(stroke
				(width 0.1524)
				(type default)
			)
			(layer "B.SilkS")
		)
		(fp_line
			(start 0.7874 -0.4064)
			(end -0.7874 -0.4064)
			(stroke
				(width 0.1524)
				(type default)
			)
			(layer "B.SilkS")
		)
		(fp_line
			(start -0.67945 0.3048)
			(end -0.120396 0.3048)
			(stroke
				(width 0.1)
				(type default)
			)
			(layer "B.Fab")
		)
		(fp_line
			(start -0.120396 0.3048)
			(end -0.120396 0.2794)
			(stroke
				(width 0.1)
				(type default)
			)
			(layer "B.Fab")
		)
		(fp_line
			(start 0.12065 0.3048)
			(end 0.67945 0.3048)
			(stroke
				(width 0.1)
				(type default)
			)
			(layer "B.Fab")
		)
		(fp_line
			(start 0.67945 0.3048)
			(end 0.67945 -0.305054)
			(stroke
				(width 0.1)
				(type default)
			)
			(layer "B.Fab")
		)
		(fp_line
			(start -0.120396 0.2794)
			(end 0.12065 0.2794)
			(stroke
				(width 0.1)
				(type default)
			)
			(layer "B.Fab")
		)
		(fp_line
			(start 0.12065 0.2794)
			(end 0.12065 0.3048)
			(stroke
				(width 0.1)
				(type default)
			)
			(layer "B.Fab")
		)
		(fp_line
			(start -0.12065 -0.2794)
			(end -0.12065 -0.3048)
			(stroke
				(width 0.1)
				(type default)
			)
			(layer "B.Fab")
		)
		(fp_line
			(start 0.12065 -0.2794)
			(end -0.12065 -0.2794)
			(stroke
				(width 0.1)
				(type default)
			)
			(layer "B.Fab")
		)
		(fp_line
			(start -0.67945 -0.3048)
			(end -0.67945 0.3048)
			(stroke
				(width 0.1)
				(type default)
			)
			(layer "B.Fab")
		)
		(fp_line
			(start -0.12065 -0.3048)
			(end -0.67945 -0.3048)
			(stroke
				(width 0.1)
				(type default)
			)
			(layer "B.Fab")
		)
		(fp_line
			(start 0.12065 -0.305054)
			(end 0.12065 -0.2794)
			(stroke
				(width 0.1)
				(type default)
			)
			(layer "B.Fab")
		)
		(fp_line
			(start 0.67945 -0.305054)
			(end 0.12065 -0.305054)
			(stroke
				(width 0.1)
				(type default)
			)
			(layer "B.Fab")
		)
		(pad "1" smd circle
			(at 0.40005 0 90)
			(size 0 0)
			(layers "B.Cu" "B.Mask" "B.Paste")
			(net "FM_UARTSW_MSB_N")
		)
		(pad "2" smd circle
			(at -0.40005 0 90)
			(size 0 0)
			(layers "B.Cu" "B.Mask" "B.Paste")
			(net "FM_UARTSW_MSB_R")
		)
	)
	(footprint ""
		(layer "B.Cu")
		(at 255.905 -335.13268 180)
		(property "Reference" "R832"
			(at 0 0 0)
			(layer "B.SilkS")
			(hide yes)
			(effects
				(font
					(size 1.27 1.27)
				)
				(justify mirror)
			)
		)
		(property "Value" ""
			(at 0 0 0)
			(layer "B.Fab")
			(effects
				(font
					(size 1.27 1.27)
				)
				(justify mirror)
			)
		)
		(duplicate_pad_numbers_are_jumpers no)
		(fp_line
			(start 0.32512 0.175006)
			(end 0.32512 -0.175006)
			(stroke
				(width 0.1)
				(type default)
			)
			(layer "B.Fab")
		)
		(fp_line
			(start 0.32512 -0.175006)
			(end -0.32512 -0.175006)
			(stroke
				(width 0.1)
				(type default)
			)
			(layer "B.Fab")
		)
		(fp_line
			(start -0.32512 0.175006)
			(end 0.32512 0.175006)
			(stroke
				(width 0.1)
				(type default)
			)
			(layer "B.Fab")
		)
		(fp_line
			(start -0.32512 -0.175006)
			(end -0.32512 0.175006)
			(stroke
				(width 0.1)
				(type default)
			)
			(layer "B.Fab")
		)
		(pad "1" smd rect
			(at 0.2667 0)
			(size 0.3048 0.381)
			(layers "B.Cu" "B.Mask" "B.Paste")
			(net "SMB_RT_CPU0_P2_ROM_MUX_2D_R_SDA")
		)
		(pad "2" smd rect
			(at -0.2667 0 180)
			(size 0.3048 0.381)
			(layers "B.Cu" "B.Mask" "B.Paste")
			(net "SMB_RT_CPU0_P2_ROM_MUX_2D_SDA")
		)
	)
	(footprint ""
		(layer "B.Cu")
		(at 136.040114 -35.866578)
		(property "Reference" "C6037"
			(at 0 0 0)
			(layer "B.SilkS")
			(hide yes)
			(effects
				(font
					(size 1.27 1.27)
				)
				(justify mirror)
			)
		)
		(property "Value" ""
			(at 0 0 0)
			(layer "B.Fab")
			(effects
				(font
					(size 1.27 1.27)
				)
				(justify mirror)
			)
		)
		(duplicate_pad_numbers_are_jumpers no)
		(fp_line
			(start -0.7874 -0.4064)
			(end -0.7874 0.4064)
			(stroke
				(width 0.1524)
				(type default)
			)
			(layer "B.SilkS")
		)
		(fp_line
			(start -0.7874 0.4064)
			(end 0.7874 0.4064)
			(stroke
				(width 0.1524)
				(type default)
			)
			(layer "B.SilkS")
		)
		(fp_line
			(start 0.7874 -0.4064)
			(end -0.7874 -0.4064)
			(stroke
				(width 0.1524)
				(type default)
			)
			(layer "B.SilkS")
		)
		(fp_line
			(start 0.7874 0.4064)
			(end 0.7874 -0.4064)
			(stroke
				(width 0.1524)
				(type default)
			)
			(layer "B.SilkS")
		)
		(fp_line
			(start -0.67945 -0.3048)
			(end -0.67945 0.3048)
			(stroke
				(width 0.1)
				(type default)
			)
			(layer "B.Fab")
		)
		(fp_line
			(start -0.67945 0.3048)
			(end -0.120396 0.3048)
			(stroke
				(width 0.1)
				(type default)
			)
			(layer "B.Fab")
		)
		(fp_line
			(start -0.12065 -0.3048)
			(end -0.67945 -0.3048)
			(stroke
				(width 0.1)
				(type default)
			)
			(layer "B.Fab")
		)
		(fp_line
			(start -0.12065 -0.2794)
			(end -0.12065 -0.3048)
			(stroke
				(width 0.1)
				(type default)
			)
			(layer "B.Fab")
		)
		(fp_line
			(start -0.120396 0.2794)
			(end 0.12065 0.2794)
			(stroke
				(width 0.1)
				(type default)
			)
			(layer "B.Fab")
		)
		(fp_line
			(start -0.120396 0.3048)
			(end -0.120396 0.2794)
			(stroke
				(width 0.1)
				(type default)
			)
			(layer "B.Fab")
		)
		(fp_line
			(start 0.12065 -0.305054)
			(end 0.12065 -0.2794)
			(stroke
				(width 0.1)
				(type default)
			)
			(layer "B.Fab")
		)
		(fp_line
			(start 0.12065 -0.2794)
			(end -0.12065 -0.2794)
			(stroke
				(width 0.1)
				(type default)
			)
			(layer "B.Fab")
		)
		(fp_line
			(start 0.12065 0.2794)
			(end 0.12065 0.3048)
			(stroke
				(width 0.1)
				(type default)
			)
			(layer "B.Fab")
		)
		(fp_line
			(start 0.12065 0.3048)
			(end 0.67945 0.3048)
			(stroke
				(width 0.1)
				(type default)
			)
			(layer "B.Fab")
		)
		(fp_line
			(start 0.67945 -0.305054)
			(end 0.12065 -0.305054)
			(stroke
				(width 0.1)
				(type default)
			)
			(layer "B.Fab")
		)
		(fp_line
			(start 0.67945 0.3048)
			(end 0.67945 -0.305054)
			(stroke
				(width 0.1)
				(type default)
			)
			(layer "B.Fab")
		)
		(pad "1" smd circle
			(at 0.40005 0 180)
			(size 0 0)
			(layers "B.Cu" "B.Mask" "B.Paste")
			(net "P1V2_CPU0_USB_DVDD12")
		)
		(pad "2" smd circle
			(at -0.40005 0 180)
			(size 0 0)
			(layers "B.Cu" "B.Mask" "B.Paste")
			(net "GND")
		)
	)
)
